# T6G (Grand Teton) — schematic netlist excerpt (pin names and nets, part order shuffled) for the footprints in the layout excerpt that follows; sources: Cadence DE-HDL packaged netlist, KiCad conversion of 04192023_DAF0TMB3IC0_F0TG_MB_C_brd_V02_OCP.brd

U8010  AP331AWG7  AP331AWG-7 IC  pkg SOT25  page 268
  \in-\  = UV_P2V5_COMP
  GND  = GND
  \in+\  = P12V_AUX_UV_TRIGGER
  OUTPUT  = IRQ_UV_DETECT_R2_N
  VCC  = P12V_AUX

PL6502  Q_INDUCTOR  1UH IND  pkg SMLF  page 361 : \1\ = SW_P1V8_RETIMER_CPU1_SW ; \2\ = P1V8_CPU1_RT_1D
PC306_5  Q_CAP  0.1UF 25V 10% X7R  pkg 0402  page 213 : A = PVDDCR_CPU0_P1_VCCS ; B = GND

(kicad_pcb
	(version 20260206)
	(generator "pcbnew")
	(generator_version "10.0")
	(general
		(thickness 1.6)
		(legacy_teardrops no)
	)
	(paper "A4")
	(title_block
		(title "04192023_DAF0TMB3IC0_F0TG_MB_C_brd_V02_OCP.brd")
		(comment 1 "Grand Teton / footprints 2044-2046 of 8354")
	)
	(layers
		(0 "F.Cu" signal "TOP")
		(4 "In1.Cu" signal "GND")
		(6 "In2.Cu" signal "IN1")
		(8 "In3.Cu" signal "GND1")
		(10 "In4.Cu" signal "IN2")
		(12 "In5.Cu" signal "GND2")
		(14 "In6.Cu" signal "IN3")
		(16 "In7.Cu" signal "GND3")
		(18 "In8.Cu" signal "VCC")
		(20 "In9.Cu" signal "VCC1")
		(22 "In10.Cu" signal "GND4")
		(24 "In11.Cu" signal "IN4")
		(26 "In12.Cu" signal "GND5")
		(28 "In13.Cu" signal "IN5")
		(30 "In14.Cu" signal "GND6")
		(32 "In15.Cu" signal "IN6")
		(34 "In16.Cu" signal "GND7")
		(2 "B.Cu" signal "BOTTOM")
		(9 "F.Adhes" user "F.Adhesive")
		(11 "B.Adhes" user "B.Adhesive")
		(13 "F.Paste" user "Package Geometry/Pastemask Top")
		(15 "B.Paste" user "Package Geometry/Pastemask Bottom")
		(5 "F.SilkS" user "Ref Des/Silkscreen Top")
		(7 "B.SilkS" user "Ref Des/Silkscreen Bottom")
		(1 "F.Mask" user "Board Geometry/Soldermask Top")
		(3 "B.Mask" user "Board Geometry/Soldermask Bottom")
		(17 "Dwgs.User" user "User.Drawings")
		(19 "Cmts.User" user "User.Comments")
		(21 "Eco1.User" user "User.Eco1")
		(23 "Eco2.User" user "User.Eco2")
		(25 "Edge.Cuts" user "Board Geometry/Outline")
		(27 "Margin" user)
		(31 "F.CrtYd" user "Package Geometry/Place Bound Top")
		(29 "B.CrtYd" user "Package Geometry/Place Bound Bottom")
		(35 "F.Fab" user "Ref Des/Assembly Top")
		(33 "B.Fab" user "Ref Des/Assembly Bottom")
	)
	(footprint ""
		(layer "F.Cu")
		(at 142.367 -117.475 180)
		(property "Reference" "U8010"
			(at 4.572 1.37033 0)
			(unlocked yes)
			(layer "F.SilkS")
			(effects
				(font
					(size 0.7874 0.5842)
					(thickness 0.1524)
				)
			)
		)
		(property "Value" ""
			(at 0 0 180)
			(layer "F.Fab")
			(effects
				(font
					(size 1.27 1.27)
				)
			)
		)
		(duplicate_pad_numbers_are_jumpers no)
		(fp_line
			(start 2.032 1.549908)
			(end -2.032 1.549908)
			(stroke
				(width 0.1524)
				(type default)
			)
			(layer "F.SilkS")
		)
		(fp_line
			(start 2.032 -1.549908)
			(end 2.032 1.549908)
			(stroke
				(width 0.1524)
				(type default)
			)
			(layer "F.SilkS")
		)
		(fp_line
			(start 0.508 -1.549908)
			(end 2.032 -1.549908)
			(stroke
				(width 0.1524)
				(type default)
			)
			(layer "F.SilkS")
		)
		(fp_line
			(start 0 -0.762)
			(end 0.508 -1.549908)
			(stroke
				(width 0.1524)
				(type default)
			)
			(layer "F.SilkS")
		)
		(fp_line
			(start -0.508 -1.549908)
			(end 0 -0.762)
			(stroke
				(width 0.1524)
				(type default)
			)
			(layer "F.SilkS")
		)
		(fp_line
			(start -2.032 1.549908)
			(end -2.032 -1.549908)
			(stroke
				(width 0.1524)
				(type default)
			)
			(layer "F.SilkS")
		)
		(fp_line
			(start -2.032 -1.549908)
			(end -0.508 -1.549908)
			(stroke
				(width 0.1524)
				(type default)
			)
			(layer "F.SilkS")
		)
		(fp_poly
			(pts
				(xy -4.349496 -1.589024) (xy -4.349496 -0.573024) (xy -3.333496 -1.081024)
			)
			(stroke
				(width 0)
				(type default)
			)
			(fill yes)
			(layer "F.SilkS")
		)
		(fp_line
			(start 0.849884 1.549908)
			(end -0.849884 1.549908)
			(stroke
				(width 0.1)
				(type default)
			)
			(layer "F.Fab")
		)
		(fp_line
			(start 0.849884 -1.549908)
			(end 0.849884 1.549908)
			(stroke
				(width 0.1)
				(type default)
			)
			(layer "F.Fab")
		)
		(fp_line
			(start -0.849884 1.549908)
			(end -0.849884 -1.549908)
			(stroke
				(width 0.1)
				(type default)
			)
			(layer "F.Fab")
		)
		(fp_line
			(start -0.849884 -1.549908)
			(end 0.849884 -1.549908)
			(stroke
				(width 0.1)
				(type default)
			)
			(layer "F.Fab")
		)
		(fp_poly
			(pts
				(xy -3.2004 -1.45796) (xy -3.2004 -0.44196) (xy -2.1844 -0.94996)
			)
			(stroke
				(width 0)
				(type default)
			)
			(fill yes)
			(layer "F.Fab")
		)
		(pad "1" smd rect
			(at -1.35001 -0.94996 90)
			(size 0.6096 1.0668)
			(layers "F.Cu" "F.Mask" "F.Paste")
			(net "UV_P2V5_COMP")
		)
		(pad "2" smd rect
			(at -1.35001 0 90)
			(size 0.6096 1.0668)
			(layers "F.Cu" "F.Mask" "F.Paste")
			(net "GND")
		)
		(pad "3" smd rect
			(at -1.35001 0.94996 90)
			(size 0.6096 1.0668)
			(layers "F.Cu" "F.Mask" "F.Paste")
			(net "P12V_AUX_UV_TRIGGER")
		)
		(pad "4" smd rect
			(at 1.35001 0.94996 90)
			(size 0.6096 1.0668)
			(layers "F.Cu" "F.Mask" "F.Paste")
			(net "IRQ_UV_DETECT_R2_N")
		)
		(pad "5" smd rect
			(at 1.35001 -0.94996 90)
			(size 0.6096 1.0668)
			(layers "F.Cu" "F.Mask" "F.Paste")
			(net "P12V_AUX")
		)
	)
	(footprint ""
		(layer "F.Cu")
		(at 229.0191 -304.162206 90)
		(property "Reference" "PL6502"
			(at -7.4422 -7.254748 90)
			(unlocked yes)
			(layer "F.SilkS")
			(effects
				(font
					(size 0.7874 0.5842)
					(thickness 0.1524)
				)
				(justify left)
			)
		)
		(property "Value" ""
			(at 0 0 90)
			(layer "F.Fab")
			(effects
				(font
					(size 1.27 1.27)
				)
			)
		)
		(duplicate_pad_numbers_are_jumpers no)
		(fp_line
			(start 7.4422 -6.400038)
			(end 7.4422 6.400038)
			(stroke
				(width 0.1524)
				(type default)
			)
			(layer "F.SilkS")
		)
		(fp_line
			(start -7.4422 -6.400038)
			(end 7.4422 -6.400038)
			(stroke
				(width 0.1524)
				(type default)
			)
			(layer "F.SilkS")
		)
		(fp_line
			(start 7.4422 6.400038)
			(end -7.4422 6.400038)
			(stroke
				(width 0.1524)
				(type default)
			)
			(layer "F.SilkS")
		)
		(fp_line
			(start -7.4422 6.400038)
			(end -7.4422 -6.400038)
			(stroke
				(width 0.1524)
				(type default)
			)
			(layer "F.SilkS")
		)
		(fp_line
			(start 6.938264 -6.400038)
			(end -6.862064 -6.400038)
			(stroke
				(width 0.1)
				(type default)
			)
			(layer "F.Fab")
		)
		(fp_line
			(start -6.862064 -6.400038)
			(end -6.862064 6.400038)
			(stroke
				(width 0.1)
				(type default)
			)
			(layer "F.Fab")
		)
		(fp_line
			(start 6.938264 6.400038)
			(end 6.938264 -6.400038)
			(stroke
				(width 0.1)
				(type default)
			)
			(layer "F.Fab")
		)
		(fp_line
			(start -6.862064 6.400038)
			(end 6.938264 6.400038)
			(stroke
				(width 0.1)
				(type default)
			)
			(layer "F.Fab")
		)
		(pad "1" smd rect
			(at -5.650484 0 90)
			(size 3.302 4.29768)
			(layers "F.Cu" "F.Mask" "F.Paste")
			(net "SW_P1V8_RETIMER_CPU1_SW")
		)
		(pad "2" smd rect
			(at 5.650484 0 90)
			(size 3.302 4.29768)
			(layers "F.Cu" "F.Mask" "F.Paste")
			(net "P1V8_CPU1_RT_1D")
		)
	)
	(footprint ""
		(layer "F.Cu")
		(at 76.654914 -172.76826 -90)
		(property "Reference" "PC306_5"
			(at 0 0 270)
			(layer "F.SilkS")
			(hide yes)
			(effects
				(font
					(size 1.27 1.27)
				)
			)
		)
		(property "Value" ""
			(at 0 0 270)
			(layer "F.Fab")
			(effects
				(font
					(size 1.27 1.27)
				)
			)
		)
		(duplicate_pad_numbers_are_jumpers no)
		(fp_line
			(start -0.7874 0.4064)
			(end -0.7874 -0.4064)
			(stroke
				(width 0.1524)
				(type default)
			)
			(layer "F.SilkS")
		)
		(fp_line
			(start 0.7874 0.4064)
			(end -0.7874 0.4064)
			(stroke
				(width 0.1524)
				(type default)
			)
			(layer "F.SilkS")
		)
		(fp_line
			(start -0.7874 -0.4064)
			(end 0.7874 -0.4064)
			(stroke
				(width 0.1524)
				(type default)
			)
			(layer "F.SilkS")
		)
		(fp_line
			(start 0.7874 -0.4064)
			(end 0.7874 0.4064)
			(stroke
				(width 0.1524)
				(type default)
			)
			(layer "F.SilkS")
		)
		(fp_line
			(start -0.67945 0.3048)
			(end -0.67945 -0.305054)
			(stroke
				(width 0.1)
				(type default)
			)
			(layer "F.Fab")
		)
		(fp_line
			(start -0.12065 0.3048)
			(end -0.67945 0.3048)
			(stroke
				(width 0.1)
				(type default)
			)
			(layer "F.Fab")
		)
		(fp_line
			(start 0.120396 0.3048)
			(end 0.120396 0.2794)
			(stroke
				(width 0.1)
				(type default)
			)
			(layer "F.Fab")
		)
		(fp_line
			(start 0.67945 0.3048)
			(end 0.120396 0.3048)
			(stroke
				(width 0.1)
				(type default)
			)
			(layer "F.Fab")
		)
		(fp_line
			(start -0.12065 0.2794)
			(end -0.12065 0.3048)
			(stroke
				(width 0.1)
				(type default)
			)
			(layer "F.Fab")
		)
		(fp_line
			(start 0.120396 0.2794)
			(end -0.12065 0.2794)
			(stroke
				(width 0.1)
				(type default)
			)
			(layer "F.Fab")
		)
		(fp_line
			(start -0.12065 -0.2794)
			(end 0.12065 -0.2794)
			(stroke
				(width 0.1)
				(type default)
			)
			(layer "F.Fab")
		)
		(fp_line
			(start 0.12065 -0.2794)
			(end 0.12065 -0.3048)
			(stroke
				(width 0.1)
				(type default)
			)
			(layer "F.Fab")
		)
		(fp_line
			(start 0.12065 -0.3048)
			(end 0.67945 -0.3048)
			(stroke
				(width 0.1)
				(type default)
			)
			(layer "F.Fab")
		)
		(fp_line
			(start 0.67945 -0.3048)
			(end 0.67945 0.3048)
			(stroke
				(width 0.1)
				(type default)
			)
			(layer "F.Fab")
		)
		(fp_line
			(start -0.67945 -0.305054)
			(end -0.12065 -0.305054)
			(stroke
				(width 0.1)
				(type default)
			)
			(layer "F.Fab")
		)
		(fp_line
			(start -0.12065 -0.305054)
			(end -0.12065 -0.2794)
			(stroke
				(width 0.1)
				(type default)
			)
			(layer "F.Fab")
		)
		(pad "1" smd circle
			(at -0.40005 0 270)
			(size 0 0)
			(layers "F.Cu" "F.Mask" "F.Paste")
			(net "PVDDCR_CPU0_P1_VCCS")
		)
		(pad "2" smd circle
			(at 0.40005 0 270)
			(size 0 0)
			(layers "F.Cu" "F.Mask" "F.Paste")
			(net "GND")
		)
	)
)
